# Barreleye-G2_Tri-mode BPX24-DVT-X01-SKU-BOM-X07-20171222_Final.xls.xlsx — Single-Sole Source Parts List (bom)
| FOXCONN TECHNOLOGY GROUP |  |  |  |  |  |  |  |  |  |  |  |  |  |  |  |  |  |
| BILL OF MATERIAL |  |  |  |  |  |  |  |  |  |  |  |  |  |  |  |  |  |
| REV OF  BOM |  | CUSTOMER | <name> |  | CUSTOMER P/N |  | PWA P/N： | PWA DESCRIPTION |  |  | PRODUCT CODE |  |  | PWA REV |  | DATE |  |
| Sourcing (Single or Sole | Critical Commodity (Y or N) | Component Class (1, 2, other) | Customer PSL (Y/N) | Item Number | Foxconn P/N | Customer P/N | Part Description | Mfr. 1 | Mfr Part # 1 | Proposed Mfr. 2 | Proposed Mfr. 2 PN | Qty | RoHS Status | Location | 2nd Source Qual Build: | Customer Comments | ODM Comments |
